# T6G (Grand Teton) — schematic netlist excerpt (pin names and nets, part order shuffled) for the footprints in the layout excerpt that follows; sources: Cadence DE-HDL packaged netlist, KiCad conversion of 04192023_DAF0TMB3IC0_F0TG_MB_C_brd_V02_OCP.brd

C446  Q_CAP  0.1UF 10V 10% X7S  pkg C0201  page 356 : A = P1V8_CPU1_RT3_1A ; B = GND
C2661  Q_CAP  22UF 4V 20% X6S  pkg C0402  page 75 : A = PVDD18_S5_P1 ; B = GND
PC8071  Q_CAP  22UF 16V 20% X6S  pkg C0805  page 190 : A = SW_P3V3_AUX_FLT ; B = GND
PC260  Q_CAP  22UF 4V 20% EMPTY  pkg C0805  page 209 : A = PVDD18_S5_P0 ; B = GND

(kicad_pcb
	(version 20260206)
	(generator "pcbnew")
	(generator_version "10.0")
	(general
		(thickness 1.6)
		(legacy_teardrops no)
	)
	(paper "A4")
	(title_block
		(title "04192023_DAF0TMB3IC0_F0TG_MB_C_brd_V02_OCP.brd")
		(comment 1 "Grand Teton / footprints 5818-5821 of 8354")
	)
	(layers
		(0 "F.Cu" signal "TOP")
		(4 "In1.Cu" signal "GND")
		(6 "In2.Cu" signal "IN1")
		(8 "In3.Cu" signal "GND1")
		(10 "In4.Cu" signal "IN2")
		(12 "In5.Cu" signal "GND2")
		(14 "In6.Cu" signal "IN3")
		(16 "In7.Cu" signal "GND3")
		(18 "In8.Cu" signal "VCC")
		(20 "In9.Cu" signal "VCC1")
		(22 "In10.Cu" signal "GND4")
		(24 "In11.Cu" signal "IN4")
		(26 "In12.Cu" signal "GND5")
		(28 "In13.Cu" signal "IN5")
		(30 "In14.Cu" signal "GND6")
		(32 "In15.Cu" signal "IN6")
		(34 "In16.Cu" signal "GND7")
		(2 "B.Cu" signal "BOTTOM")
		(9 "F.Adhes" user "F.Adhesive")
		(11 "B.Adhes" user "B.Adhesive")
		(13 "F.Paste" user "Package Geometry/Pastemask Top")
		(15 "B.Paste" user "Package Geometry/Pastemask Bottom")
		(5 "F.SilkS" user "Ref Des/Silkscreen Top")
		(7 "B.SilkS" user "Ref Des/Silkscreen Bottom")
		(1 "F.Mask" user "Board Geometry/Soldermask Top")
		(3 "B.Mask" user "Board Geometry/Soldermask Bottom")
		(17 "Dwgs.User" user "User.Drawings")
		(19 "Cmts.User" user "User.Comments")
		(21 "Eco1.User" user "User.Eco1")
		(23 "Eco2.User" user "User.Eco2")
		(25 "Edge.Cuts" user "Board Geometry/Outline")
		(27 "Margin" user)
		(31 "F.CrtYd" user "Package Geometry/Place Bound Top")
		(29 "B.CrtYd" user "Package Geometry/Place Bound Bottom")
		(35 "F.Fab" user "Ref Des/Assembly Top")
		(33 "B.Fab" user "Ref Des/Assembly Bottom")
	)
	(footprint ""
		(layer "B.Cu")
		(at 98.60534 -254.956564)
		(property "Reference" "C2661"
			(at 0 0 0)
			(layer "B.SilkS")
			(hide yes)
			(effects
				(font
					(size 1.27 1.27)
				)
				(justify mirror)
			)
		)
		(property "Value" ""
			(at 0 0 0)
			(layer "B.Fab")
			(effects
				(font
					(size 1.27 1.27)
				)
				(justify mirror)
			)
		)
		(duplicate_pad_numbers_are_jumpers no)
		(fp_line
			(start -0.7874 -0.4064)
			(end -0.7874 0.4064)
			(stroke
				(width 0.1524)
				(type default)
			)
			(layer "B.SilkS")
		)
		(fp_line
			(start -0.7874 0.4064)
			(end 0.7874 0.4064)
			(stroke
				(width 0.1524)
				(type default)
			)
			(layer "B.SilkS")
		)
		(fp_line
			(start 0.7874 -0.4064)
			(end -0.7874 -0.4064)
			(stroke
				(width 0.1524)
				(type default)
			)
			(layer "B.SilkS")
		)
		(fp_line
			(start 0.7874 0.4064)
			(end 0.7874 -0.4064)
			(stroke
				(width 0.1524)
				(type default)
			)
			(layer "B.SilkS")
		)
		(fp_line
			(start -0.67945 -0.3048)
			(end -0.67945 0.3048)
			(stroke
				(width 0.1)
				(type default)
			)
			(layer "B.Fab")
		)
		(fp_line
			(start -0.67945 0.3048)
			(end -0.120396 0.3048)
			(stroke
				(width 0.1)
				(type default)
			)
			(layer "B.Fab")
		)
		(fp_line
			(start -0.12065 -0.3048)
			(end -0.67945 -0.3048)
			(stroke
				(width 0.1)
				(type default)
			)
			(layer "B.Fab")
		)
		(fp_line
			(start -0.12065 -0.2794)
			(end -0.12065 -0.3048)
			(stroke
				(width 0.1)
				(type default)
			)
			(layer "B.Fab")
		)
		(fp_line
			(start -0.120396 0.2794)
			(end 0.12065 0.2794)
			(stroke
				(width 0.1)
				(type default)
			)
			(layer "B.Fab")
		)
		(fp_line
			(start -0.120396 0.3048)
			(end -0.120396 0.2794)
			(stroke
				(width 0.1)
				(type default)
			)
			(layer "B.Fab")
		)
		(fp_line
			(start 0.12065 -0.305054)
			(end 0.12065 -0.2794)
			(stroke
				(width 0.1)
				(type default)
			)
			(layer "B.Fab")
		)
		(fp_line
			(start 0.12065 -0.2794)
			(end -0.12065 -0.2794)
			(stroke
				(width 0.1)
				(type default)
			)
			(layer "B.Fab")
		)
		(fp_line
			(start 0.12065 0.2794)
			(end 0.12065 0.3048)
			(stroke
				(width 0.1)
				(type default)
			)
			(layer "B.Fab")
		)
		(fp_line
			(start 0.12065 0.3048)
			(end 0.67945 0.3048)
			(stroke
				(width 0.1)
				(type default)
			)
			(layer "B.Fab")
		)
		(fp_line
			(start 0.67945 -0.305054)
			(end 0.12065 -0.305054)
			(stroke
				(width 0.1)
				(type default)
			)
			(layer "B.Fab")
		)
		(fp_line
			(start 0.67945 0.3048)
			(end 0.67945 -0.305054)
			(stroke
				(width 0.1)
				(type default)
			)
			(layer "B.Fab")
		)
		(pad "1" smd circle
			(at 0.40005 0 180)
			(size 0 0)
			(layers "B.Cu" "B.Mask" "B.Paste")
			(net "PVDD18_S5_P1")
		)
		(pad "2" smd circle
			(at -0.40005 0 180)
			(size 0 0)
			(layers "B.Cu" "B.Mask" "B.Paste")
			(net "GND")
		)
	)
	(footprint ""
		(layer "B.Cu")
		(at 121.678446 -386.766562 90)
		(property "Reference" "C446"
			(at 0 0 90)
			(layer "B.SilkS")
			(hide yes)
			(effects
				(font
					(size 1.27 1.27)
				)
				(justify mirror)
			)
		)
		(property "Value" ""
			(at 0 0 90)
			(layer "B.Fab")
			(effects
				(font
					(size 1.27 1.27)
				)
				(justify mirror)
			)
		)
		(duplicate_pad_numbers_are_jumpers no)
		(fp_line
			(start 0.299974 -0.150114)
			(end -0.299974 -0.150114)
			(stroke
				(width 0.1)
				(type default)
			)
			(layer "B.Fab")
		)
		(fp_line
			(start -0.299974 -0.150114)
			(end -0.299974 0.150114)
			(stroke
				(width 0.1)
				(type default)
			)
			(layer "B.Fab")
		)
		(fp_line
			(start 0.299974 0.150114)
			(end 0.299974 -0.150114)
			(stroke
				(width 0.1)
				(type default)
			)
			(layer "B.Fab")
		)
		(fp_line
			(start -0.299974 0.150114)
			(end 0.299974 0.150114)
			(stroke
				(width 0.1)
				(type default)
			)
			(layer "B.Fab")
		)
		(pad "1" smd rect
			(at 0.2667 0 270)
			(size 0.3048 0.381)
			(layers "B.Cu" "B.Mask" "B.Paste")
			(net "P1V8_CPU1_RT3_1A")
		)
		(pad "2" smd rect
			(at -0.2667 0 270)
			(size 0.3048 0.381)
			(layers "B.Cu" "B.Mask" "B.Paste")
			(net "GND")
		)
	)
	(footprint ""
		(layer "B.Cu")
		(at 335.618836 -151.069294 90)
		(property "Reference" "PC260"
			(at 0 0 90)
			(layer "B.SilkS")
			(hide yes)
			(effects
				(font
					(size 1.27 1.27)
				)
				(justify mirror)
			)
		)
		(property "Value" ""
			(at 0 0 90)
			(layer "B.Fab")
			(effects
				(font
					(size 1.27 1.27)
				)
				(justify mirror)
			)
		)
		(duplicate_pad_numbers_are_jumpers no)
		(fp_line
			(start 1.524 -0.762)
			(end -1.524 -0.762)
			(stroke
				(width 0.1524)
				(type default)
			)
			(layer "B.SilkS")
		)
		(fp_line
			(start -1.524 -0.762)
			(end -1.524 0.762)
			(stroke
				(width 0.1524)
				(type default)
			)
			(layer "B.SilkS")
		)
		(fp_line
			(start 1.524 0.762)
			(end 1.524 -0.762)
			(stroke
				(width 0.1524)
				(type default)
			)
			(layer "B.SilkS")
		)
		(fp_line
			(start -1.524 0.762)
			(end 1.524 0.762)
			(stroke
				(width 0.1524)
				(type default)
			)
			(layer "B.SilkS")
		)
		(fp_line
			(start 1.1049 -0.724916)
			(end 1.1049 0.724916)
			(stroke
				(width 0.1)
				(type default)
			)
			(layer "B.Fab")
		)
		(fp_line
			(start -1.1049 -0.724916)
			(end 1.1049 -0.724916)
			(stroke
				(width 0.1)
				(type default)
			)
			(layer "B.Fab")
		)
		(fp_line
			(start 1.1049 0.724916)
			(end -1.1049 0.724916)
			(stroke
				(width 0.1)
				(type default)
			)
			(layer "B.Fab")
		)
		(fp_line
			(start -1.1049 0.724916)
			(end -1.1049 -0.724916)
			(stroke
				(width 0.1)
				(type default)
			)
			(layer "B.Fab")
		)
		(pad "1" smd rect
			(at 0.889 0 90)
			(size 1.016 1.27)
			(layers "B.Cu" "B.Mask" "B.Paste")
			(net "PVDD18_S5_P0")
		)
		(pad "2" smd rect
			(at -0.889 0 90)
			(size 1.016 1.27)
			(layers "B.Cu" "B.Mask" "B.Paste")
			(net "GND")
		)
	)
	(footprint ""
		(layer "B.Cu")
		(at 451.577456 -52.849526 -90)
		(property "Reference" "PC8071"
			(at 0 0 90)
			(layer "B.SilkS")
			(hide yes)
			(effects
				(font
					(size 1.27 1.27)
				)
				(justify mirror)
			)
		)
		(property "Value" ""
			(at 0 0 90)
			(layer "B.Fab")
			(effects
				(font
					(size 1.27 1.27)
				)
				(justify mirror)
			)
		)
		(duplicate_pad_numbers_are_jumpers no)
		(fp_line
			(start -1.524 0.762)
			(end 1.524 0.762)
			(stroke
				(width 0.1524)
				(type default)
			)
			(layer "B.SilkS")
		)
		(fp_line
			(start 1.524 0.762)
			(end 1.524 -0.762)
			(stroke
				(width 0.1524)
				(type default)
			)
			(layer "B.SilkS")
		)
		(fp_line
			(start -1.524 -0.762)
			(end -1.524 0.762)
			(stroke
				(width 0.1524)
				(type default)
			)
			(layer "B.SilkS")
		)
		(fp_line
			(start 1.524 -0.762)
			(end -1.524 -0.762)
			(stroke
				(width 0.1524)
				(type default)
			)
			(layer "B.SilkS")
		)
		(fp_line
			(start -1.1049 0.724916)
			(end -1.1049 -0.724916)
			(stroke
				(width 0.1)
				(type default)
			)
			(layer "B.Fab")
		)
		(fp_line
			(start 1.1049 0.724916)
			(end -1.1049 0.724916)
			(stroke
				(width 0.1)
				(type default)
			)
			(layer "B.Fab")
		)
		(fp_line
			(start -1.1049 -0.724916)
			(end 1.1049 -0.724916)
			(stroke
				(width 0.1)
				(type default)
			)
			(layer "B.Fab")
		)
		(fp_line
			(start 1.1049 -0.724916)
			(end 1.1049 0.724916)
			(stroke
				(width 0.1)
				(type default)
			)
			(layer "B.Fab")
		)
		(pad "1" smd rect
			(at 0.889 0 270)
			(size 1.016 1.27)
			(layers "B.Cu" "B.Mask" "B.Paste")
			(net "SW_P3V3_AUX_FLT")
		)
		(pad "2" smd rect
			(at -0.889 0 270)
			(size 1.016 1.27)
			(layers "B.Cu" "B.Mask" "B.Paste")
			(net "GND")
		)
	)
)
